# S9S_MB_2U (Grand Teton) — schematic netlist excerpt (pin names and nets, part order shuffled) for the footprints in the layout excerpt that follows; sources: Cadence DE-HDL packaged netlist, KiCad conversion of 03242023_DA0F0TMBIJ0_F0T_Motherboard_J_brd_V01_OCP.brd

R4131  Q_RES  54.9K 1% EMPTY  pkg 0402LF  page 146 : A = P3V3_AUX ; B = GPU_3V3IO_RSVD3_FFU
R2134  Q_RES  10K 1% CHIP  pkg 0402LF  page 201 : A = JTAG_TRC_PCH_PTI<6> ; B = GND
C1532  Q_CAP_DIFFBUS  DIFF BUS_0.22UF 6.3V 20% X6S  pkg C0201  page 177 : \1\ = P5E_CPU1_PE3_TX_C_DN<7> ; \2\ = P5E_CPU1_PE3_TX_DN<7>

(kicad_pcb
	(version 20260206)
	(generator "pcbnew")
	(generator_version "10.0")
	(general
		(thickness 1.6)
		(legacy_teardrops no)
	)
	(paper "A4")
	(title_block
		(title "03242023_DA0F0TMBIJ0_F0T_Motherboard_J_brd_V01_OCP.brd")
		(comment 1 "Grand Teton / footprints 1439-1441 of 6105")
	)
	(layers
		(0 "F.Cu" signal "TOP")
		(4 "In1.Cu" signal "GND")
		(6 "In2.Cu" signal "IN1")
		(8 "In3.Cu" signal "GND1")
		(10 "In4.Cu" signal "IN2")
		(12 "In5.Cu" signal "GND2")
		(14 "In6.Cu" signal "IN3")
		(16 "In7.Cu" signal "GND3")
		(18 "In8.Cu" signal "VCC")
		(20 "In9.Cu" signal "VCC1")
		(22 "In10.Cu" signal "GND4")
		(24 "In11.Cu" signal "IN4")
		(26 "In12.Cu" signal "GND5")
		(28 "In13.Cu" signal "IN5")
		(30 "In14.Cu" signal "GND6")
		(32 "In15.Cu" signal "IN6")
		(34 "In16.Cu" signal "GND7")
		(2 "B.Cu" signal "BOTTOM")
		(9 "F.Adhes" user "F.Adhesive")
		(11 "B.Adhes" user "B.Adhesive")
		(13 "F.Paste" user "Package Geometry/Pastemask Top")
		(15 "B.Paste" user "Package Geometry/Pastemask Bottom")
		(5 "F.SilkS" user "Ref Des/Silkscreen Top")
		(7 "B.SilkS" user "Ref Des/Silkscreen Bottom")
		(1 "F.Mask" user "Board Geometry/Soldermask Top")
		(3 "B.Mask" user "Board Geometry/Soldermask Bottom")
		(17 "Dwgs.User" user "User.Drawings")
		(19 "Cmts.User" user "User.Comments")
		(21 "Eco1.User" user "User.Eco1")
		(23 "Eco2.User" user "User.Eco2")
		(25 "Edge.Cuts" user "Board Geometry/Outline")
		(27 "Margin" user)
		(31 "F.CrtYd" user "Package Geometry/Place Bound Top")
		(29 "B.CrtYd" user "Package Geometry/Place Bound Bottom")
		(35 "F.Fab" user "Ref Des/Assembly Top")
		(33 "B.Fab" user "Ref Des/Assembly Bottom")
	)
	(footprint ""
		(layer "F.Cu")
		(at 302.85436 -433.04587 90)
		(property "Reference" "R4131"
			(at 0 0 90)
			(layer "F.SilkS")
			(hide yes)
			(effects
				(font
					(size 1.27 1.27)
				)
			)
		)
		(property "Value" ""
			(at 0 0 90)
			(layer "F.Fab")
			(effects
				(font
					(size 1.27 1.27)
				)
			)
		)
		(duplicate_pad_numbers_are_jumpers no)
		(fp_line
			(start 0.7874 -0.4064)
			(end 0.7874 0.4064)
			(stroke
				(width 0.1524)
				(type default)
			)
			(layer "F.SilkS")
		)
		(fp_line
			(start -0.7874 -0.4064)
			(end 0.7874 -0.4064)
			(stroke
				(width 0.1524)
				(type default)
			)
			(layer "F.SilkS")
		)
		(fp_line
			(start 0.7874 0.4064)
			(end -0.7874 0.4064)
			(stroke
				(width 0.1524)
				(type default)
			)
			(layer "F.SilkS")
		)
		(fp_line
			(start -0.7874 0.4064)
			(end -0.7874 -0.4064)
			(stroke
				(width 0.1524)
				(type default)
			)
			(layer "F.SilkS")
		)
		(fp_line
			(start -0.12065 -0.305054)
			(end -0.12065 -0.2794)
			(stroke
				(width 0.1)
				(type default)
			)
			(layer "F.Fab")
		)
		(fp_line
			(start -0.67945 -0.305054)
			(end -0.12065 -0.305054)
			(stroke
				(width 0.1)
				(type default)
			)
			(layer "F.Fab")
		)
		(fp_line
			(start 0.67945 -0.3048)
			(end 0.67945 0.3048)
			(stroke
				(width 0.1)
				(type default)
			)
			(layer "F.Fab")
		)
		(fp_line
			(start 0.12065 -0.3048)
			(end 0.67945 -0.3048)
			(stroke
				(width 0.1)
				(type default)
			)
			(layer "F.Fab")
		)
		(fp_line
			(start 0.12065 -0.2794)
			(end 0.12065 -0.3048)
			(stroke
				(width 0.1)
				(type default)
			)
			(layer "F.Fab")
		)
		(fp_line
			(start -0.12065 -0.2794)
			(end 0.12065 -0.2794)
			(stroke
				(width 0.1)
				(type default)
			)
			(layer "F.Fab")
		)
		(fp_line
			(start 0.120396 0.2794)
			(end -0.12065 0.2794)
			(stroke
				(width 0.1)
				(type default)
			)
			(layer "F.Fab")
		)
		(fp_line
			(start -0.12065 0.2794)
			(end -0.12065 0.3048)
			(stroke
				(width 0.1)
				(type default)
			)
			(layer "F.Fab")
		)
		(fp_line
			(start 0.67945 0.3048)
			(end 0.120396 0.3048)
			(stroke
				(width 0.1)
				(type default)
			)
			(layer "F.Fab")
		)
		(fp_line
			(start 0.120396 0.3048)
			(end 0.120396 0.2794)
			(stroke
				(width 0.1)
				(type default)
			)
			(layer "F.Fab")
		)
		(fp_line
			(start -0.12065 0.3048)
			(end -0.67945 0.3048)
			(stroke
				(width 0.1)
				(type default)
			)
			(layer "F.Fab")
		)
		(fp_line
			(start -0.67945 0.3048)
			(end -0.67945 -0.305054)
			(stroke
				(width 0.1)
				(type default)
			)
			(layer "F.Fab")
		)
		(pad "1" smd circle
			(at -0.40005 0 90)
			(size 0 0)
			(layers "F.Cu" "F.Mask" "F.Paste")
			(net "P3V3_AUX")
		)
		(pad "2" smd circle
			(at 0.40005 0 90)
			(size 0 0)
			(layers "F.Cu" "F.Mask" "F.Paste")
			(net "GPU_3V3IO_RSVD3_FFU")
		)
	)
	(footprint ""
		(layer "F.Cu")
		(at 145.981674 -408.517344 -90)
		(property "Reference" "C1532"
			(at 0 0 270)
			(layer "F.SilkS")
			(hide yes)
			(effects
				(font
					(size 1.27 1.27)
				)
			)
		)
		(property "Value" ""
			(at 0 0 270)
			(layer "F.Fab")
			(effects
				(font
					(size 1.27 1.27)
				)
			)
		)
		(duplicate_pad_numbers_are_jumpers no)
		(fp_line
			(start -0.299974 0.150114)
			(end -0.299974 -0.150114)
			(stroke
				(width 0.1)
				(type default)
			)
			(layer "F.Fab")
		)
		(fp_line
			(start 0.299974 0.150114)
			(end -0.299974 0.150114)
			(stroke
				(width 0.1)
				(type default)
			)
			(layer "F.Fab")
		)
		(fp_line
			(start -0.299974 -0.150114)
			(end 0.299974 -0.150114)
			(stroke
				(width 0.1)
				(type default)
			)
			(layer "F.Fab")
		)
		(fp_line
			(start 0.299974 -0.150114)
			(end 0.299974 0.150114)
			(stroke
				(width 0.1)
				(type default)
			)
			(layer "F.Fab")
		)
		(pad "1" smd rect
			(at -0.2667 0 270)
			(size 0.3048 0.381)
			(layers "F.Cu" "F.Mask" "F.Paste")
			(net "P5E_CPU1_PE3_TX_C_DN<7>")
		)
		(pad "2" smd rect
			(at 0.2667 0 270)
			(size 0.3048 0.381)
			(layers "F.Cu" "F.Mask" "F.Paste")
			(net "P5E_CPU1_PE3_TX_DN<7>")
		)
	)
	(footprint ""
		(layer "F.Cu")
		(at 435.157118 -44.44238)
		(property "Reference" "R2134"
			(at 0 0 0)
			(layer "F.SilkS")
			(hide yes)
			(effects
				(font
					(size 1.27 1.27)
				)
			)
		)
		(property "Value" ""
			(at 0 0 0)
			(layer "F.Fab")
			(effects
				(font
					(size 1.27 1.27)
				)
			)
		)
		(duplicate_pad_numbers_are_jumpers no)
		(fp_line
			(start -0.7874 -0.4064)
			(end 0.7874 -0.4064)
			(stroke
				(width 0.1524)
				(type default)
			)
			(layer "F.SilkS")
		)
		(fp_line
			(start -0.7874 0.4064)
			(end -0.7874 -0.4064)
			(stroke
				(width 0.1524)
				(type default)
			)
			(layer "F.SilkS")
		)
		(fp_line
			(start 0.7874 -0.4064)
			(end 0.7874 0.4064)
			(stroke
				(width 0.1524)
				(type default)
			)
			(layer "F.SilkS")
		)
		(fp_line
			(start 0.7874 0.4064)
			(end -0.7874 0.4064)
			(stroke
				(width 0.1524)
				(type default)
			)
			(layer "F.SilkS")
		)
		(fp_line
			(start -0.67945 -0.305054)
			(end -0.12065 -0.305054)
			(stroke
				(width 0.1)
				(type default)
			)
			(layer "F.Fab")
		)
		(fp_line
			(start -0.67945 0.3048)
			(end -0.67945 -0.305054)
			(stroke
				(width 0.1)
				(type default)
			)
			(layer "F.Fab")
		)
		(fp_line
			(start -0.12065 -0.305054)
			(end -0.12065 -0.2794)
			(stroke
				(width 0.1)
				(type default)
			)
			(layer "F.Fab")
		)
		(fp_line
			(start -0.12065 -0.2794)
			(end 0.12065 -0.2794)
			(stroke
				(width 0.1)
				(type default)
			)
			(layer "F.Fab")
		)
		(fp_line
			(start -0.12065 0.2794)
			(end -0.12065 0.3048)
			(stroke
				(width 0.1)
				(type default)
			)
			(layer "F.Fab")
		)
		(fp_line
			(start -0.12065 0.3048)
			(end -0.67945 0.3048)
			(stroke
				(width 0.1)
				(type default)
			)
			(layer "F.Fab")
		)
		(fp_line
			(start 0.120396 0.2794)
			(end -0.12065 0.2794)
			(stroke
				(width 0.1)
				(type default)
			)
			(layer "F.Fab")
		)
		(fp_line
			(start 0.120396 0.3048)
			(end 0.120396 0.2794)
			(stroke
				(width 0.1)
				(type default)
			)
			(layer "F.Fab")
		)
		(fp_line
			(start 0.12065 -0.3048)
			(end 0.67945 -0.3048)
			(stroke
				(width 0.1)
				(type default)
			)
			(layer "F.Fab")
		)
		(fp_line
			(start 0.12065 -0.2794)
			(end 0.12065 -0.3048)
			(stroke
				(width 0.1)
				(type default)
			)
			(layer "F.Fab")
		)
		(fp_line
			(start 0.67945 -0.3048)
			(end 0.67945 0.3048)
			(stroke
				(width 0.1)
				(type default)
			)
			(layer "F.Fab")
		)
		(fp_line
			(start 0.67945 0.3048)
			(end 0.120396 0.3048)
			(stroke
				(width 0.1)
				(type default)
			)
			(layer "F.Fab")
		)
		(pad "1" smd circle
			(at -0.40005 0)
			(size 0 0)
			(layers "F.Cu" "F.Mask" "F.Paste")
			(net "JTAG_TRC_PCH_PTI<6>")
		)
		(pad "2" smd circle
			(at 0.40005 0)
			(size 0 0)
			(layers "F.Cu" "F.Mask" "F.Paste")
			(net "GND")
		)
	)
)
